# T6G (Grand Teton) — schematic netlist excerpt (pin names and nets, part order shuffled) for the footprints in the layout excerpt that follows; sources: Cadence DE-HDL packaged netlist, KiCad conversion of 04192023_DAF0TMB3IC0_F0TG_MB_C_brd_V02_OCP.brd

Q63  MOSFET_N  BSS138K IC  pkg SMLF  page 174
  DRAIN  = FM_PLD_CPU0_PRSNT_HDT_N
  GATE  = CPU0_HDT_BYPASS_SEL
  SOURCE  = GND

C5014  Q_CAP  1000PF 50V 5% X7R  pkg 0402  page 259 : A = PWRGD_P12V_MEM_R ; B = GND
PC6564  Q_CAP  560PF 50V 10% EMPTY  pkg C0402  page 363 : A = SW_P0V9_RETIMER_CPU0_SW1 ; B = SW_P0V9_RETIMER_CPU0_SW1_RC

(kicad_pcb
	(version 20260206)
	(generator "pcbnew")
	(generator_version "10.0")
	(general
		(thickness 1.6)
		(legacy_teardrops no)
	)
	(paper "A4")
	(title_block
		(title "04192023_DAF0TMB3IC0_F0TG_MB_C_brd_V02_OCP.brd")
		(comment 1 "Grand Teton / footprints 1920-1922 of 8354")
	)
	(layers
		(0 "F.Cu" signal "TOP")
		(4 "In1.Cu" signal "GND")
		(6 "In2.Cu" signal "IN1")
		(8 "In3.Cu" signal "GND1")
		(10 "In4.Cu" signal "IN2")
		(12 "In5.Cu" signal "GND2")
		(14 "In6.Cu" signal "IN3")
		(16 "In7.Cu" signal "GND3")
		(18 "In8.Cu" signal "VCC")
		(20 "In9.Cu" signal "VCC1")
		(22 "In10.Cu" signal "GND4")
		(24 "In11.Cu" signal "IN4")
		(26 "In12.Cu" signal "GND5")
		(28 "In13.Cu" signal "IN5")
		(30 "In14.Cu" signal "GND6")
		(32 "In15.Cu" signal "IN6")
		(34 "In16.Cu" signal "GND7")
		(2 "B.Cu" signal "BOTTOM")
		(9 "F.Adhes" user "F.Adhesive")
		(11 "B.Adhes" user "B.Adhesive")
		(13 "F.Paste" user "Package Geometry/Pastemask Top")
		(15 "B.Paste" user "Package Geometry/Pastemask Bottom")
		(5 "F.SilkS" user "Ref Des/Silkscreen Top")
		(7 "B.SilkS" user "Ref Des/Silkscreen Bottom")
		(1 "F.Mask" user "Board Geometry/Soldermask Top")
		(3 "B.Mask" user "Board Geometry/Soldermask Bottom")
		(17 "Dwgs.User" user "User.Drawings")
		(19 "Cmts.User" user "User.Comments")
		(21 "Eco1.User" user "User.Eco1")
		(23 "Eco2.User" user "User.Eco2")
		(25 "Edge.Cuts" user "Board Geometry/Outline")
		(27 "Margin" user)
		(31 "F.CrtYd" user "Package Geometry/Place Bound Top")
		(29 "B.CrtYd" user "Package Geometry/Place Bound Bottom")
		(35 "F.Fab" user "Ref Des/Assembly Top")
		(33 "B.Fab" user "Ref Des/Assembly Bottom")
	)
	(footprint ""
		(layer "F.Cu")
		(at 97.074736 -119.469154 90)
		(property "Reference" "C5014"
			(at 0 0 90)
			(layer "F.SilkS")
			(hide yes)
			(effects
				(font
					(size 1.27 1.27)
				)
			)
		)
		(property "Value" ""
			(at 0 0 90)
			(layer "F.Fab")
			(effects
				(font
					(size 1.27 1.27)
				)
			)
		)
		(duplicate_pad_numbers_are_jumpers no)
		(fp_line
			(start 0.7874 -0.4064)
			(end 0.7874 0.4064)
			(stroke
				(width 0.1524)
				(type default)
			)
			(layer "F.SilkS")
		)
		(fp_line
			(start -0.7874 -0.4064)
			(end 0.7874 -0.4064)
			(stroke
				(width 0.1524)
				(type default)
			)
			(layer "F.SilkS")
		)
		(fp_line
			(start 0.7874 0.4064)
			(end -0.7874 0.4064)
			(stroke
				(width 0.1524)
				(type default)
			)
			(layer "F.SilkS")
		)
		(fp_line
			(start -0.7874 0.4064)
			(end -0.7874 -0.4064)
			(stroke
				(width 0.1524)
				(type default)
			)
			(layer "F.SilkS")
		)
		(fp_line
			(start -0.12065 -0.305054)
			(end -0.12065 -0.2794)
			(stroke
				(width 0.1)
				(type default)
			)
			(layer "F.Fab")
		)
		(fp_line
			(start -0.67945 -0.305054)
			(end -0.12065 -0.305054)
			(stroke
				(width 0.1)
				(type default)
			)
			(layer "F.Fab")
		)
		(fp_line
			(start 0.67945 -0.3048)
			(end 0.67945 0.3048)
			(stroke
				(width 0.1)
				(type default)
			)
			(layer "F.Fab")
		)
		(fp_line
			(start 0.12065 -0.3048)
			(end 0.67945 -0.3048)
			(stroke
				(width 0.1)
				(type default)
			)
			(layer "F.Fab")
		)
		(fp_line
			(start 0.12065 -0.2794)
			(end 0.12065 -0.3048)
			(stroke
				(width 0.1)
				(type default)
			)
			(layer "F.Fab")
		)
		(fp_line
			(start -0.12065 -0.2794)
			(end 0.12065 -0.2794)
			(stroke
				(width 0.1)
				(type default)
			)
			(layer "F.Fab")
		)
		(fp_line
			(start 0.120396 0.2794)
			(end -0.12065 0.2794)
			(stroke
				(width 0.1)
				(type default)
			)
			(layer "F.Fab")
		)
		(fp_line
			(start -0.12065 0.2794)
			(end -0.12065 0.3048)
			(stroke
				(width 0.1)
				(type default)
			)
			(layer "F.Fab")
		)
		(fp_line
			(start 0.67945 0.3048)
			(end 0.120396 0.3048)
			(stroke
				(width 0.1)
				(type default)
			)
			(layer "F.Fab")
		)
		(fp_line
			(start 0.120396 0.3048)
			(end 0.120396 0.2794)
			(stroke
				(width 0.1)
				(type default)
			)
			(layer "F.Fab")
		)
		(fp_line
			(start -0.12065 0.3048)
			(end -0.67945 0.3048)
			(stroke
				(width 0.1)
				(type default)
			)
			(layer "F.Fab")
		)
		(fp_line
			(start -0.67945 0.3048)
			(end -0.67945 -0.305054)
			(stroke
				(width 0.1)
				(type default)
			)
			(layer "F.Fab")
		)
		(pad "1" smd circle
			(at -0.40005 0 90)
			(size 0 0)
			(layers "F.Cu" "F.Mask" "F.Paste")
			(net "PWRGD_P12V_MEM_R")
		)
		(pad "2" smd circle
			(at 0.40005 0 90)
			(size 0 0)
			(layers "F.Cu" "F.Mask" "F.Paste")
			(net "GND")
		)
	)
	(footprint ""
		(layer "F.Cu")
		(at 234.771946 -141.805152)
		(property "Reference" "Q63"
			(at -3.24866 -1.300988 0)
			(unlocked yes)
			(layer "F.SilkS")
			(effects
				(font
					(size 0.7874 0.5842)
					(thickness 0.1524)
				)
			)
		)
		(property "Value" ""
			(at 0 0 0)
			(layer "F.Fab")
			(effects
				(font
					(size 1.27 1.27)
				)
			)
		)
		(duplicate_pad_numbers_are_jumpers no)
		(fp_line
			(start -1.949958 -1.610106)
			(end 1.949958 -1.610106)
			(stroke
				(width 0.1524)
				(type default)
			)
			(layer "F.SilkS")
		)
		(fp_line
			(start -1.949958 1.610106)
			(end -1.949958 -1.610106)
			(stroke
				(width 0.1524)
				(type default)
			)
			(layer "F.SilkS")
		)
		(fp_line
			(start 1.949958 -1.560068)
			(end 1.949958 1.610106)
			(stroke
				(width 0.1524)
				(type default)
			)
			(layer "F.SilkS")
		)
		(fp_line
			(start 1.949958 1.610106)
			(end -1.949958 1.610106)
			(stroke
				(width 0.1524)
				(type default)
			)
			(layer "F.SilkS")
		)
		(fp_line
			(start -0.750062 -1.560068)
			(end 0.750062 -1.560068)
			(stroke
				(width 0.1)
				(type default)
			)
			(layer "F.Fab")
		)
		(fp_line
			(start -0.750062 1.560068)
			(end -0.750062 -1.560068)
			(stroke
				(width 0.1)
				(type default)
			)
			(layer "F.Fab")
		)
		(fp_line
			(start 0.750062 -1.560068)
			(end 0.750062 1.560068)
			(stroke
				(width 0.1)
				(type default)
			)
			(layer "F.Fab")
		)
		(fp_line
			(start 0.750062 1.560068)
			(end -0.750062 1.560068)
			(stroke
				(width 0.1)
				(type default)
			)
			(layer "F.Fab")
		)
		(pad "D" smd rect
			(at 1.100074 0 270)
			(size 1.016 1.4224)
			(layers "F.Cu" "F.Mask" "F.Paste")
			(net "FM_PLD_CPU0_PRSNT_HDT_N")
		)
		(pad "G" smd rect
			(at -1.100074 -0.94996 270)
			(size 1.016 1.4224)
			(layers "F.Cu" "F.Mask" "F.Paste")
			(net "CPU0_HDT_BYPASS_SEL")
		)
		(pad "S" smd rect
			(at -1.100074 0.94996 270)
			(size 1.016 1.4224)
			(layers "F.Cu" "F.Mask" "F.Paste")
			(net "GND")
		)
	)
	(footprint ""
		(layer "F.Cu")
		(at 441.31103 -394.302234 180)
		(property "Reference" "PC6564"
			(at 0 0 180)
			(layer "F.SilkS")
			(hide yes)
			(effects
				(font
					(size 1.27 1.27)
				)
			)
		)
		(property "Value" ""
			(at 0 0 180)
			(layer "F.Fab")
			(effects
				(font
					(size 1.27 1.27)
				)
			)
		)
		(duplicate_pad_numbers_are_jumpers no)
		(fp_line
			(start 0.7874 0.4064)
			(end -0.7874 0.4064)
			(stroke
				(width 0.1524)
				(type default)
			)
			(layer "F.SilkS")
		)
		(fp_line
			(start 0.7874 -0.4064)
			(end 0.7874 0.4064)
			(stroke
				(width 0.1524)
				(type default)
			)
			(layer "F.SilkS")
		)
		(fp_line
			(start -0.7874 0.4064)
			(end -0.7874 -0.4064)
			(stroke
				(width 0.1524)
				(type default)
			)
			(layer "F.SilkS")
		)
		(fp_line
			(start -0.7874 -0.4064)
			(end 0.7874 -0.4064)
			(stroke
				(width 0.1524)
				(type default)
			)
			(layer "F.SilkS")
		)
		(fp_line
			(start 0.67945 0.3048)
			(end 0.120396 0.3048)
			(stroke
				(width 0.1)
				(type default)
			)
			(layer "F.Fab")
		)
		(fp_line
			(start 0.67945 -0.3048)
			(end 0.67945 0.3048)
			(stroke
				(width 0.1)
				(type default)
			)
			(layer "F.Fab")
		)
		(fp_line
			(start 0.12065 -0.2794)
			(end 0.12065 -0.3048)
			(stroke
				(width 0.1)
				(type default)
			)
			(layer "F.Fab")
		)
		(fp_line
			(start 0.12065 -0.3048)
			(end 0.67945 -0.3048)
			(stroke
				(width 0.1)
				(type default)
			)
			(layer "F.Fab")
		)
		(fp_line
			(start 0.120396 0.3048)
			(end 0.120396 0.2794)
			(stroke
				(width 0.1)
				(type default)
			)
			(layer "F.Fab")
		)
		(fp_line
			(start 0.120396 0.2794)
			(end -0.12065 0.2794)
			(stroke
				(width 0.1)
				(type default)
			)
			(layer "F.Fab")
		)
		(fp_line
			(start -0.12065 0.3048)
			(end -0.67945 0.3048)
			(stroke
				(width 0.1)
				(type default)
			)
			(layer "F.Fab")
		)
		(fp_line
			(start -0.12065 0.2794)
			(end -0.12065 0.3048)
			(stroke
				(width 0.1)
				(type default)
			)
			(layer "F.Fab")
		)
		(fp_line
			(start -0.12065 -0.2794)
			(end 0.12065 -0.2794)
			(stroke
				(width 0.1)
				(type default)
			)
			(layer "F.Fab")
		)
		(fp_line
			(start -0.12065 -0.305054)
			(end -0.12065 -0.2794)
			(stroke
				(width 0.1)
				(type default)
			)
			(layer "F.Fab")
		)
		(fp_line
			(start -0.67945 0.3048)
			(end -0.67945 -0.305054)
			(stroke
				(width 0.1)
				(type default)
			)
			(layer "F.Fab")
		)
		(fp_line
			(start -0.67945 -0.305054)
			(end -0.12065 -0.305054)
			(stroke
				(width 0.1)
				(type default)
			)
			(layer "F.Fab")
		)
		(pad "1" smd circle
			(at -0.40005 0 180)
			(size 0 0)
			(layers "F.Cu" "F.Mask" "F.Paste")
			(net "SW_P0V9_RETIMER_CPU0_SW1")
		)
		(pad "2" smd circle
			(at 0.40005 0 180)
			(size 0 0)
			(layers "F.Cu" "F.Mask" "F.Paste")
			(net "SW_P0V9_RETIMER_CPU0_SW1_RC")
		)
	)
)
